FILE_TYPE=LIBRARY_PARTS;
primitive 'MAX15090BEWIT';
  pin
    'VCC':
      PIN_NUMBER='(A2)';
      PINUSE='POWER';
      NO_LOAD_CHECK='Both';
      NO_IO_CHECK='Both';
      NO_ASSERT_CHECK='TRUE';
      NO_DIR_CHECK='TRUE';
      ALLOW_CONNECT='TRUE';
    'IN_A3':
      PIN_NUMBER='(A3)';
      INPUT_LOAD='(-0.01,0.01)';
    'IN_A5':
      PIN_NUMBER='(A5)';
      INPUT_LOAD='(-0.01,0.01)';
    'IN_B3':
      PIN_NUMBER='(B3)';
      INPUT_LOAD='(-0.01,0.01)';
    'IN_B5':
      PIN_NUMBER='(B5)';
      INPUT_LOAD='(-0.01,0.01)';
    'IN_C3':
      PIN_NUMBER='(C3)';
      INPUT_LOAD='(-0.01,0.01)';
    'IN_C5':
      PIN_NUMBER='(C5)';
      INPUT_LOAD='(-0.01,0.01)';
    'IN_D5':
      PIN_NUMBER='(D5)';
      INPUT_LOAD='(-0.01,0.01)';
    'CB':
      PIN_NUMBER='(B1)';
      BIDIRECTIONAL='TRUE';
      INPUT_LOAD='(-0.01,0.01)';
      OUTPUT_LOAD='(1.0,-1.0)';
    'EN#':
      PIN_NUMBER='(B7)';
      INPUT_LOAD='(-0.01,0.01)';
    'REG':
      PIN_NUMBER='(D1)';
      OUTPUT_LOAD='(1.0,-1.0)';
    'UV':
      PIN_NUMBER='(D2)';
      INPUT_LOAD='(-0.01,0.01)';
    'OV':
      PIN_NUMBER='(D3)';
      INPUT_LOAD='(-0.01,0.01)';
    'ISENSE':
      PIN_NUMBER='(A1)';
      OUTPUT_LOAD='(1.0,-1.0)';
    'OUT_A4':
      PIN_NUMBER='(A4)';
      OUTPUT_LOAD='(1.0,-1.0)';
    'OUT_B4':
      PIN_NUMBER='(B4)';
      OUTPUT_LOAD='(1.0,-1.0)';
    'OUT_B6':
      PIN_NUMBER='(B6)';
      OUTPUT_LOAD='(1.0,-1.0)';
    'OUT_C4':
      PIN_NUMBER='(C4)';
      OUTPUT_LOAD='(1.0,-1.0)';
    'OUT_C6':
      PIN_NUMBER='(C6)';
      OUTPUT_LOAD='(1.0,-1.0)';
    'OUT_D4':
      PIN_NUMBER='(D4)';
      OUTPUT_LOAD='(1.0,-1.0)';
    'OUT_D6':
      PIN_NUMBER='(D6)';
      OUTPUT_LOAD='(1.0,-1.0)';
    'GATE':
      PIN_NUMBER='(A6)';
      BIDIRECTIONAL='TRUE';
      INPUT_LOAD='(-0.01,0.01)';
      OUTPUT_LOAD='(1.0,-1.0)';
    'CDLY':
      PIN_NUMBER='(A7)';
      INPUT_LOAD='(-0.01,0.01)';
    'GND_B2':
      PIN_NUMBER='(B2)';
      PINUSE='POWER';
      NO_LOAD_CHECK='Both';
      NO_IO_CHECK='Both';
      NO_ASSERT_CHECK='TRUE';
      NO_DIR_CHECK='TRUE';
      ALLOW_CONNECT='TRUE';
    'GND_C1':
      PIN_NUMBER='(C1)';
      PINUSE='POWER';
      NO_LOAD_CHECK='Both';
      NO_IO_CHECK='Both';
      NO_ASSERT_CHECK='TRUE';
      NO_DIR_CHECK='TRUE';
      ALLOW_CONNECT='TRUE';
    'GND_C2':
      PIN_NUMBER='(C2)';
      PINUSE='POWER';
      NO_LOAD_CHECK='Both';
      NO_IO_CHECK='Both';
      NO_ASSERT_CHECK='TRUE';
      NO_DIR_CHECK='TRUE';
      ALLOW_CONNECT='TRUE';
    'FAULT#':
      PIN_NUMBER='(C7)';
      OUTPUT_LOAD='(1.0,-1.0)';
    'PG':
      PIN_NUMBER='(D7)';
      OUTPUT_LOAD='(1.0,-1.0)';
  end_pin;
  body
    PART_NAME='MAX15090BEWIT';
    BODY_NAME='MAX15090BEWIT';
    PHYS_DES_PREFIX='U';
    CLASS='IC';
  end_body;
end_primitive;

END.
